(kicad_pcb
	(version 20260206)
	(generator "pcbnew")
	(generator_version "10.0")
	(general
		(thickness 1.6)
		(legacy_teardrops no)
	)
	(paper "A4")
	(title_block
		(title "v1-chassis-manager — T6M_CM_d_v01_1031_1645.brd")
		(comment 1 "Open CloudServer (Microsoft) / footprints 1002-1009 of 2512")
	)
	(layers
		(0 "F.Cu" signal "TOP")
		(4 "In1.Cu" signal "GND1")
		(6 "In2.Cu" signal "IN1")
		(8 "In3.Cu" signal "VCC1")
		(10 "In4.Cu" signal "VCC2")
		(12 "In5.Cu" signal "GND2")
		(14 "In6.Cu" signal "IN2")
		(16 "In7.Cu" signal "IN3")
		(18 "In8.Cu" signal "GND3")
		(2 "B.Cu" signal "BOTTOM")
		(9 "F.Adhes" user "F.Adhesive")
		(11 "B.Adhes" user "B.Adhesive")
		(13 "F.Paste" user "Package Geometry/Pastemask Top")
		(15 "B.Paste" user "Package Geometry/Pastemask Bottom")
		(5 "F.SilkS" user "Ref Des/Silkscreen Top")
		(7 "B.SilkS" user "Ref Des/Silkscreen Bottom")
		(1 "F.Mask" user "Board Geometry/Soldermask Top")
		(3 "B.Mask" user "Board Geometry/Soldermask Bottom")
		(17 "Dwgs.User" user "User.Drawings")
		(19 "Cmts.User" user "User.Comments")
		(21 "Eco1.User" user "User.Eco1")
		(23 "Eco2.User" user "User.Eco2")
		(25 "Edge.Cuts" user "Board Geometry/Outline")
		(27 "Margin" user)
		(31 "F.CrtYd" user "Package Geometry/Place Bound Top")
		(29 "B.CrtYd" user "Package Geometry/Place Bound Bottom")
		(35 "F.Fab" user "Ref Des/Assembly Top")
		(33 "B.Fab" user "Ref Des/Assembly Bottom")
	)
	(footprint ""
		(layer "F.Cu")
		(at 137.65276 -185.205624 -90)
		(property "Reference" "R882"
			(at -4.768088 0.474472 90)
			(unlocked yes)
			(layer "F.SilkS")
			(effects
				(font
					(size 0.7874 0.5842)
					(thickness 0.1524)
				)
				(justify left)
			)
		)
		(property "Value" ""
			(at 0 0 270)
			(layer "F.Fab")
			(effects
				(font
					(size 1.27 1.27)
				)
			)
		)
		(duplicate_pad_numbers_are_jumpers no)
		(fp_line
			(start -0.7874 0.4064)
			(end -0.7874 -0.4064)
			(stroke
				(width 0.1524)
				(type default)
			)
			(layer "F.SilkS")
		)
		(fp_line
			(start 0.7874 0.4064)
			(end -0.7874 0.4064)
			(stroke
				(width 0.1524)
				(type default)
			)
			(layer "F.SilkS")
		)
		(fp_line
			(start -0.7874 -0.4064)
			(end 0.7874 -0.4064)
			(stroke
				(width 0.1524)
				(type default)
			)
			(layer "F.SilkS")
		)
		(fp_line
			(start 0.7874 -0.4064)
			(end 0.7874 0.4064)
			(stroke
				(width 0.1524)
				(type default)
			)
			(layer "F.SilkS")
		)
		(fp_poly
			(pts
				(xy -0.508 0.2794) (xy -0.508 0.2286) (xy -0.635 0.2286) (xy -0.635 -0.254) (xy -0.5334 -0.254)
				(xy -0.5334 -0.2794) (xy 0.5334 -0.2794) (xy 0.5334 -0.254) (xy 0.635 -0.254) (xy 0.635 0.254) (xy 0.5334 0.254)
				(xy 0.5334 0.2794)
			)
			(stroke
				(width 0)
				(type default)
			)
			(fill no)
			(layer "F.CrtYd")
		)
		(pad "1" smd rect
			(at 0.40005 0 270)
			(size 0.4572 0.508)
			(layers "F.Cu" "F.Mask" "F.Paste")
			(net "T10_NODE4_EN")
		)
		(pad "2" smd rect
			(at -0.40005 0 270)
			(size 0.4572 0.508)
			(layers "F.Cu" "F.Mask" "F.Paste")
			(net "T10_NODE4_EN_R")
		)
	)
	(footprint ""
		(layer "F.Cu")
		(at 152.579578 -70.203822 180)
		(property "Reference" "R504"
			(at 1.658366 2.26695 0)
			(unlocked yes)
			(layer "F.SilkS")
			(effects
				(font
					(size 0.7874 0.5842)
					(thickness 0.1524)
				)
				(justify left)
			)
		)
		(property "Value" ""
			(at 0 0 180)
			(layer "F.Fab")
			(effects
				(font
					(size 1.27 1.27)
				)
			)
		)
		(duplicate_pad_numbers_are_jumpers no)
		(fp_line
			(start 0.7874 0.4064)
			(end -0.7874 0.4064)
			(stroke
				(width 0.1524)
				(type default)
			)
			(layer "F.SilkS")
		)
		(fp_line
			(start 0.7874 -0.4064)
			(end 0.7874 0.4064)
			(stroke
				(width 0.1524)
				(type default)
			)
			(layer "F.SilkS")
		)
		(fp_line
			(start -0.7874 0.4064)
			(end -0.7874 -0.4064)
			(stroke
				(width 0.1524)
				(type default)
			)
			(layer "F.SilkS")
		)
		(fp_line
			(start -0.7874 -0.4064)
			(end 0.7874 -0.4064)
			(stroke
				(width 0.1524)
				(type default)
			)
			(layer "F.SilkS")
		)
		(fp_poly
			(pts
				(xy -0.508 0.2794) (xy -0.508 0.2286) (xy -0.635 0.2286) (xy -0.635 -0.254) (xy -0.5334 -0.254)
				(xy -0.5334 -0.2794) (xy 0.5334 -0.2794) (xy 0.5334 -0.254) (xy 0.635 -0.254) (xy 0.635 0.254) (xy 0.5334 0.254)
				(xy 0.5334 0.2794)
			)
			(stroke
				(width 0)
				(type default)
			)
			(fill no)
			(layer "F.CrtYd")
		)
		(pad "1" smd rect
			(at 0.40005 0 180)
			(size 0.4572 0.508)
			(layers "F.Cu" "F.Mask" "F.Paste")
			(net "SATA_NODE1_ISET")
		)
		(pad "2" smd rect
			(at -0.40005 0 180)
			(size 0.4572 0.508)
			(layers "F.Cu" "F.Mask" "F.Paste")
			(net "GND")
		)
	)
	(footprint ""
		(layer "F.Cu")
		(at 16.486124 -52.32908 -90)
		(property "Reference" "R638"
			(at 4.444492 -14.374114 90)
			(unlocked yes)
			(layer "F.SilkS")
			(effects
				(font
					(size 0.7874 0.5842)
					(thickness 0.1524)
				)
				(justify left)
			)
		)
		(property "Value" ""
			(at 0 0 270)
			(layer "F.Fab")
			(effects
				(font
					(size 1.27 1.27)
				)
			)
		)
		(duplicate_pad_numbers_are_jumpers no)
		(fp_line
			(start -0.7874 0.4064)
			(end -0.7874 -0.4064)
			(stroke
				(width 0.1524)
				(type default)
			)
			(layer "F.SilkS")
		)
		(fp_line
			(start 0.7874 0.4064)
			(end -0.7874 0.4064)
			(stroke
				(width 0.1524)
				(type default)
			)
			(layer "F.SilkS")
		)
		(fp_line
			(start -0.7874 -0.4064)
			(end 0.7874 -0.4064)
			(stroke
				(width 0.1524)
				(type default)
			)
			(layer "F.SilkS")
		)
		(fp_line
			(start 0.7874 -0.4064)
			(end 0.7874 0.4064)
			(stroke
				(width 0.1524)
				(type default)
			)
			(layer "F.SilkS")
		)
		(fp_poly
			(pts
				(xy -0.508 0.2794) (xy -0.508 0.2286) (xy -0.635 0.2286) (xy -0.635 -0.254) (xy -0.5334 -0.254)
				(xy -0.5334 -0.2794) (xy 0.5334 -0.2794) (xy 0.5334 -0.254) (xy 0.635 -0.254) (xy 0.635 0.254) (xy 0.5334 0.254)
				(xy 0.5334 0.2794)
			)
			(stroke
				(width 0)
				(type default)
			)
			(fill no)
			(layer "F.CrtYd")
		)
		(pad "1" smd rect
			(at 0.40005 0 270)
			(size 0.4572 0.508)
			(layers "F.Cu" "F.Mask" "F.Paste")
			(net "VGA_HSYNC")
		)
		(pad "2" smd rect
			(at -0.40005 0 270)
			(size 0.4572 0.508)
			(layers "F.Cu" "F.Mask" "F.Paste")
			(net "CRT_HSYNC")
		)
	)
	(footprint ""
		(layer "F.Cu")
		(at 155.350972 -33.459928 90)
		(property "Reference" "U51"
			(at -3.49377 5.493512 90)
			(unlocked yes)
			(layer "F.SilkS")
			(effects
				(font
					(size 0.7874 0.5842)
					(thickness 0.1524)
				)
				(justify left)
			)
		)
		(property "Value" ""
			(at 0 0 90)
			(layer "F.Fab")
			(effects
				(font
					(size 1.27 1.27)
				)
			)
		)
		(duplicate_pad_numbers_are_jumpers no)
		(fp_line
			(start 4.9022 -2.0066)
			(end 4.9022 2.0066)
			(stroke
				(width 0.1524)
				(type default)
			)
			(layer "F.SilkS")
		)
		(fp_line
			(start -4.9022 -2.0066)
			(end 4.9022 -2.0066)
			(stroke
				(width 0.1524)
				(type default)
			)
			(layer "F.SilkS")
		)
		(fp_line
			(start -4.9022 -0.5842)
			(end -4.9022 -2.0066)
			(stroke
				(width 0.1524)
				(type default)
			)
			(layer "F.SilkS")
		)
		(fp_line
			(start -4.318 0)
			(end -4.9022 -0.5842)
			(stroke
				(width 0.1524)
				(type default)
			)
			(layer "F.SilkS")
		)
		(fp_line
			(start -4.9022 0.5842)
			(end -4.318 0)
			(stroke
				(width 0.1524)
				(type default)
			)
			(layer "F.SilkS")
		)
		(fp_line
			(start 4.9022 2.0066)
			(end -4.9022 2.0066)
			(stroke
				(width 0.1524)
				(type default)
			)
			(layer "F.SilkS")
		)
		(fp_line
			(start -4.9022 2.0066)
			(end -4.9022 0.5842)
			(stroke
				(width 0.1524)
				(type default)
			)
			(layer "F.SilkS")
		)
		(fp_circle
			(center -4.318 1.524)
			(end -4.318 1.778)
			(stroke
				(width 0.1524)
				(type default)
			)
			(fill no)
			(layer "F.SilkS")
		)
		(fp_rect
			(start -4.9022 3.6703)
			(end 4.9022 -3.6703)
			(stroke
				(width 0)
				(type default)
			)
			(fill no)
			(layer "F.CrtYd")
		)
		(pad "1" smd rect
			(at -4.225036 2.921 90)
			(size 0.3556 1.4986)
			(layers "F.Cu" "F.Mask" "F.Paste")
			(net "N21624861")
		)
		(pad "2" smd rect
			(at -3.57505 2.921 90)
			(size 0.3556 1.4986)
			(layers "F.Cu" "F.Mask" "F.Paste")
			(net "N21624866")
		)
		(pad "3" smd rect
			(at -2.925064 2.921 90)
			(size 0.3556 1.4986)
			(layers "F.Cu" "F.Mask" "F.Paste")
			(net "N21624894")
		)
		(pad "4" smd rect
			(at -2.275078 2.921 90)
			(size 0.3556 1.4986)
			(layers "F.Cu" "F.Mask" "F.Paste")
			(net "UART_RX_P1_L")
		)
		(pad "5" smd rect
			(at -1.625092 2.921 90)
			(size 0.3556 1.4986)
			(layers "F.Cu" "F.Mask" "F.Paste")
			(net "UART_DSR_P1_L_N")
		)
		(pad "6" smd rect
			(at -0.975106 2.921 90)
			(size 0.3556 1.4986)
			(layers "F.Cu" "F.Mask" "F.Paste")
			(net "UART_CTS_P1_L_N")
		)
		(pad "7" smd rect
			(at -0.32512 2.921 90)
			(size 0.3556 1.4986)
			(layers "F.Cu" "F.Mask" "F.Paste")
			(net "N37284163")
		)
		(pad "8" smd rect
			(at 0.32512 2.921 90)
			(size 0.3556 1.4986)
			(layers "F.Cu" "F.Mask" "F.Paste")
			(net "N37284163")
		)
		(pad "9" smd rect
			(at 0.975106 2.921 90)
			(size 0.3556 1.4986)
			(layers "F.Cu" "F.Mask" "F.Paste")
			(net "UART_RTS_P1_L_N")
		)
		(pad "10" smd rect
			(at 1.625092 2.921 90)
			(size 0.3556 1.4986)
			(layers "F.Cu" "F.Mask" "F.Paste")
			(net "UART_TX_P1_L")
		)
		(pad "11" smd rect
			(at 2.275078 2.921 90)
			(size 0.3556 1.4986)
			(layers "F.Cu" "F.Mask" "F.Paste")
			(net "UART_DTR_P1_L_N")
		)
		(pad "12" smd rect
			(at 2.925064 2.921 90)
			(size 0.3556 1.4986)
			(layers "F.Cu" "F.Mask" "F.Paste")
			(net "UART_DTR_P1_N")
		)
		(pad "13" smd rect
			(at 3.57505 2.921 90)
			(size 0.3556 1.4986)
			(layers "F.Cu" "F.Mask" "F.Paste")
			(net "UART_TX_P1")
		)
		(pad "14" smd rect
			(at 4.225036 2.921 90)
			(size 0.3556 1.4986)
			(layers "F.Cu" "F.Mask" "F.Paste")
			(net "UART_RTS_P1_N")
		)
		(pad "15" smd rect
			(at 4.225036 -2.921 90)
			(size 0.3556 1.4986)
			(layers "F.Cu" "F.Mask" "F.Paste")
			(net "Net_503")
		)
		(pad "16" smd rect
			(at 3.57505 -2.921 90)
			(size 0.3556 1.4986)
			(layers "F.Cu" "F.Mask" "F.Paste")
			(net "Net_504")
		)
		(pad "17" smd rect
			(at 2.925064 -2.921 90)
			(size 0.3556 1.4986)
			(layers "F.Cu" "F.Mask" "F.Paste")
			(net "UART_CTS_P1_N")
		)
		(pad "18" smd rect
			(at 2.275078 -2.921 90)
			(size 0.3556 1.4986)
			(layers "F.Cu" "F.Mask" "F.Paste")
			(net "UART_DSR_P1_N")
		)
		(pad "19" smd rect
			(at 1.625092 -2.921 90)
			(size 0.3556 1.4986)
			(layers "F.Cu" "F.Mask" "F.Paste")
			(net "UART_RX_P1")
		)
		(pad "20" smd rect
			(at 0.975106 -2.921 90)
			(size 0.3556 1.4986)
			(layers "F.Cu" "F.Mask" "F.Paste")
			(net "Net_1849")
		)
		(pad "21" smd rect
			(at 0.32512 -2.921 90)
			(size 0.3556 1.4986)
			(layers "F.Cu" "F.Mask" "F.Paste")
			(net "Net_1848")
		)
		(pad "22" smd rect
			(at -0.32512 -2.921 90)
			(size 0.3556 1.4986)
			(layers "F.Cu" "F.Mask" "F.Paste")
			(net "N21624806")
		)
		(pad "23" smd rect
			(at -0.975106 -2.921 90)
			(size 0.3556 1.4986)
			(layers "F.Cu" "F.Mask" "F.Paste")
			(net "N21624804")
		)
		(pad "24" smd rect
			(at -1.625092 -2.921 90)
			(size 0.3556 1.4986)
			(layers "F.Cu" "F.Mask" "F.Paste")
			(net "N21624850")
		)
		(pad "25" smd rect
			(at -2.275078 -2.921 90)
			(size 0.3556 1.4986)
			(layers "F.Cu" "F.Mask" "F.Paste")
			(net "GND")
		)
		(pad "26" smd rect
			(at -2.925064 -2.921 90)
			(size 0.3556 1.4986)
			(layers "F.Cu" "F.Mask" "F.Paste")
			(net "P3V3_NODE1")
		)
		(pad "27" smd rect
			(at -3.57505 -2.921 90)
			(size 0.3556 1.4986)
			(layers "F.Cu" "F.Mask" "F.Paste")
			(net "N21624890")
		)
		(pad "28" smd rect
			(at -4.225036 -2.921 90)
			(size 0.3556 1.4986)
			(layers "F.Cu" "F.Mask" "F.Paste")
			(net "N21624848")
		)
	)
	(footprint ""
		(layer "F.Cu")
		(at 149.633178 -73.937622 90)
		(property "Reference" "C333"
			(at -0.780034 2.370074 90)
			(unlocked yes)
			(layer "F.SilkS")
			(effects
				(font
					(size 0.7874 0.5842)
					(thickness 0.1524)
				)
				(justify left)
			)
		)
		(property "Value" ""
			(at 0 0 90)
			(layer "F.Fab")
			(effects
				(font
					(size 1.27 1.27)
				)
			)
		)
		(duplicate_pad_numbers_are_jumpers no)
		(fp_line
			(start 0.7874 -0.4064)
			(end 0.7874 0.4064)
			(stroke
				(width 0.1524)
				(type default)
			)
			(layer "F.SilkS")
		)
		(fp_line
			(start -0.7874 -0.4064)
			(end 0.7874 -0.4064)
			(stroke
				(width 0.1524)
				(type default)
			)
			(layer "F.SilkS")
		)
		(fp_line
			(start 0 0.381)
			(end 0 -0.381)
			(stroke
				(width 0.1524)
				(type default)
			)
			(layer "F.SilkS")
		)
		(fp_line
			(start 0.7874 0.4064)
			(end -0.7874 0.4064)
			(stroke
				(width 0.1524)
				(type default)
			)
			(layer "F.SilkS")
		)
		(fp_line
			(start -0.7874 0.4064)
			(end -0.7874 -0.4064)
			(stroke
				(width 0.1524)
				(type default)
			)
			(layer "F.SilkS")
		)
		(fp_poly
			(pts
				(xy -0.5334 0.254) (xy -0.635 0.254) (xy -0.635 0.2286) (xy -0.635 -0.254) (xy -0.5334 -0.254) (xy -0.5334 -0.2794)
				(xy 0.5334 -0.2794) (xy 0.5334 -0.254) (xy 0.635 -0.254) (xy 0.635 0.254) (xy 0.5334 0.254) (xy 0.5334 0.2794)
				(xy -0.508 0.2794) (xy -0.5334 0.2794)
			)
			(stroke
				(width 0)
				(type default)
			)
			(fill no)
			(layer "F.CrtYd")
		)
		(pad "1" smd rect
			(at 0.40005 0 90)
			(size 0.4572 0.508)
			(layers "F.Cu" "F.Mask" "F.Paste")
			(net "P2E_CPU_SATA_NODE1_RX_DP")
		)
		(pad "2" smd rect
			(at -0.40005 0 90)
			(size 0.4572 0.508)
			(layers "F.Cu" "F.Mask" "F.Paste")
			(net "P2E_CPU_SATA_NODE1_RX_C_DP")
		)
	)
	(footprint ""
		(layer "F.Cu")
		(at 80.502252 -103.795576 90)
		(property "Reference" "R1099"
			(at -1.475486 -0.10033 0)
			(unlocked yes)
			(layer "F.SilkS")
			(effects
				(font
					(size 0.7874 0.5842)
					(thickness 0.1524)
				)
				(justify left)
			)
		)
		(property "Value" ""
			(at 0 0 90)
			(layer "F.Fab")
			(effects
				(font
					(size 1.27 1.27)
				)
			)
		)
		(duplicate_pad_numbers_are_jumpers no)
		(fp_line
			(start 0.7874 -0.4064)
			(end 0.7874 0.4064)
			(stroke
				(width 0.1524)
				(type default)
			)
			(layer "F.SilkS")
		)
		(fp_line
			(start -0.7874 -0.4064)
			(end 0.7874 -0.4064)
			(stroke
				(width 0.1524)
				(type default)
			)
			(layer "F.SilkS")
		)
		(fp_line
			(start 0.7874 0.4064)
			(end -0.7874 0.4064)
			(stroke
				(width 0.1524)
				(type default)
			)
			(layer "F.SilkS")
		)
		(fp_line
			(start -0.7874 0.4064)
			(end -0.7874 -0.4064)
			(stroke
				(width 0.1524)
				(type default)
			)
			(layer "F.SilkS")
		)
		(fp_poly
			(pts
				(xy -0.508 0.2794) (xy -0.508 0.2286) (xy -0.635 0.2286) (xy -0.635 -0.254) (xy -0.5334 -0.254)
				(xy -0.5334 -0.2794) (xy 0.5334 -0.2794) (xy 0.5334 -0.254) (xy 0.635 -0.254) (xy 0.635 0.254) (xy 0.5334 0.254)
				(xy 0.5334 0.2794)
			)
			(stroke
				(width 0)
				(type default)
			)
			(fill no)
			(layer "F.CrtYd")
		)
		(pad "1" smd rect
			(at 0.40005 0 90)
			(size 0.4572 0.508)
			(layers "F.Cu" "F.Mask" "F.Paste")
			(net "P12V_AUX")
		)
		(pad "2" smd rect
			(at -0.40005 0 90)
			(size 0.4572 0.508)
			(layers "F.Cu" "F.Mask" "F.Paste")
			(net "FM_CPLD_NODE1_P3V3_SUS_EN_LV")
		)
	)
	(footprint ""
		(layer "F.Cu")
		(at 20.921472 -74.207878 -90)
		(property "Reference" "C497"
			(at -1.699514 -0.002794 90)
			(unlocked yes)
			(layer "F.SilkS")
			(effects
				(font
					(size 0.7874 0.5842)
					(thickness 0.1524)
				)
				(justify left)
			)
		)
		(property "Value" ""
			(at 0 0 270)
			(layer "F.Fab")
			(effects
				(font
					(size 1.27 1.27)
				)
			)
		)
		(duplicate_pad_numbers_are_jumpers no)
		(fp_line
			(start -0.7874 0.4064)
			(end -0.7874 -0.4064)
			(stroke
				(width 0.1524)
				(type default)
			)
			(layer "F.SilkS")
		)
		(fp_line
			(start 0.7874 0.4064)
			(end -0.7874 0.4064)
			(stroke
				(width 0.1524)
				(type default)
			)
			(layer "F.SilkS")
		)
		(fp_line
			(start 0 0.381)
			(end 0 -0.381)
			(stroke
				(width 0.1524)
				(type default)
			)
			(layer "F.SilkS")
		)
		(fp_line
			(start -0.7874 -0.4064)
			(end 0.7874 -0.4064)
			(stroke
				(width 0.1524)
				(type default)
			)
			(layer "F.SilkS")
		)
		(fp_line
			(start 0.7874 -0.4064)
			(end 0.7874 0.4064)
			(stroke
				(width 0.1524)
				(type default)
			)
			(layer "F.SilkS")
		)
		(fp_poly
			(pts
				(xy -0.5334 0.254) (xy -0.635 0.254) (xy -0.635 0.2286) (xy -0.635 -0.254) (xy -0.5334 -0.254) (xy -0.5334 -0.2794)
				(xy 0.5334 -0.2794) (xy 0.5334 -0.254) (xy 0.635 -0.254) (xy 0.635 0.254) (xy 0.5334 0.254) (xy 0.5334 0.2794)
				(xy -0.508 0.2794) (xy -0.5334 0.2794)
			)
			(stroke
				(width 0)
				(type default)
			)
			(fill no)
			(layer "F.CrtYd")
		)
		(pad "1" smd rect
			(at 0.40005 0 270)
			(size 0.4572 0.508)
			(layers "F.Cu" "F.Mask" "F.Paste")
			(net "P5V_NODE1")
		)
		(pad "2" smd rect
			(at -0.40005 0 270)
			(size 0.4572 0.508)
			(layers "F.Cu" "F.Mask" "F.Paste")
			(net "GND")
		)
	)
	(footprint ""
		(layer "F.Cu")
		(at 47.649892 -112.875568 180)
		(property "Reference" "PC12"
			(at 1.286002 3.150108 0)
			(unlocked yes)
			(layer "F.SilkS")
			(effects
				(font
					(size 0.7874 0.5842)
					(thickness 0.1524)
				)
				(justify left)
			)
		)
		(property "Value" ""
			(at 0 0 180)
			(layer "F.Fab")
			(effects
				(font
					(size 1.27 1.27)
				)
			)
		)
		(duplicate_pad_numbers_are_jumpers no)
		(fp_line
			(start 0.7874 0.4064)
			(end -0.7874 0.4064)
			(stroke
				(width 0.1524)
				(type default)
			)
			(layer "F.SilkS")
		)
		(fp_line
			(start 0.7874 -0.4064)
			(end 0.7874 0.4064)
			(stroke
				(width 0.1524)
				(type default)
			)
			(layer "F.SilkS")
		)
		(fp_line
			(start 0 0.381)
			(end 0 -0.381)
			(stroke
				(width 0.1524)
				(type default)
			)
			(layer "F.SilkS")
		)
		(fp_line
			(start -0.7874 0.4064)
			(end -0.7874 -0.4064)
			(stroke
				(width 0.1524)
				(type default)
			)
			(layer "F.SilkS")
		)
		(fp_line
			(start -0.7874 -0.4064)
			(end 0.7874 -0.4064)
			(stroke
				(width 0.1524)
				(type default)
			)
			(layer "F.SilkS")
		)
		(fp_poly
			(pts
				(xy -0.5334 0.254) (xy -0.635 0.254) (xy -0.635 0.2286) (xy -0.635 -0.254) (xy -0.5334 -0.254) (xy -0.5334 -0.2794)
				(xy 0.5334 -0.2794) (xy 0.5334 -0.254) (xy 0.635 -0.254) (xy 0.635 0.254) (xy 0.5334 0.254) (xy 0.5334 0.2794)
				(xy -0.508 0.2794) (xy -0.5334 0.2794)
			)
			(stroke
				(width 0)
				(type default)
			)
			(fill no)
			(layer "F.CrtYd")
		)
		(pad "1" smd rect
			(at 0.40005 0 180)
			(size 0.4572 0.508)
			(layers "F.Cu" "F.Mask" "F.Paste")
			(net "P12V_AUX")
		)
		(pad "2" smd rect
			(at -0.40005 0 180)
			(size 0.4572 0.508)
			(layers "F.Cu" "F.Mask" "F.Paste")
			(net "GND")
		)
	)
)
